# SO-DIMM DDR5 Tester — KiCad custom design rules (.kicad_dru)
(version 1)

(rule "50OHM_SE_outer" 
	(constraint track_width (opt 0.256mm))
	(constraint clearance (opt 0.1mm))
	(condition "(A.NetClass == '50Ohm-se')")
	(layer outer)
)

(rule "50OHM_SE_inner" 
	(constraint track_width (opt 0.1mm))
	(constraint clearance (opt 0.1mm))
	(condition "(A.NetClass == '50Ohm-se')")
	(layer inner)
)

(rule "PCIe_85Ohm_outer" 
# calculated as 85Ohm @ 50 Ohm SE
	(constraint track_width (opt 0.22mm) )
	(constraint diff_pair_gap (opt 0.16mm))
	(constraint clearance (opt 0.1mm))
	(condition "(A.NetClass == '85Ohm-diff_PCIe')")
	(layer outer)
)

(rule "PCIe_85Ohm_outer_FPGA" 
# calculated as 85Ohm @ 50 Ohm SE
	(constraint track_width (opt 0.1mm) )
	(constraint diff_pair_gap (opt 0.1mm))
	(constraint clearance (opt 0.1mm))
	(condition "A.NetClass == '85Ohm-diff_PCIe' && A.insideCourtyard('U3002')")
	(layer outer)
)

(rule "DDR_80OHM_diff_outer" 
# calculated as 80Ohm @ 45 Ohm SE
	(constraint track_width (opt 0.26mm))
	(constraint diff_pair_gap (opt 0.2mm))
	(constraint clearance (opt 0.1mm))
	(condition "(A.NetClass == '80Ohm-diff_DQS') ")
	(layer outer)
)

(rule "DDR_40OHM_SE_outer" 
	(constraint track_width (opt 0.38mm))
	(constraint clearance (opt 0.1mm))
	(condition "(A.NetClass == '40Ohm-se_DQ')")
	(layer outer)
)

(rule "DDR_80OHM_diff_inner" 
# calculated as 80Ohm @ 45 Ohm SE
	(constraint track_width (opt 0.13mm))
	(constraint diff_pair_gap (opt 0.11mm))
	(constraint clearance (opt 0.1mm))
	(condition "(A.NetClass == '80Ohm-diff_DQS') ")
	(layer inner)
)

(rule "DDR_40OHM_SE_inner" 
	(constraint track_width (opt 0.148mm))
	(constraint clearance (opt 0.1mm))
	(condition "(A.NetClass == '40Ohm-se_DQ')")
	(layer inner)
)

(rule "100OHM_diff_inner" 
# calculated as 95Ohm @ 51 Ohm SE
	(constraint track_width (opt 0.1mm))
	(constraint diff_pair_gap (opt 0.15mm))
	(constraint clearance (opt 0.1mm))
	(condition "(A.NetClass == '100Ohm-diff') ")
	(layer inner)
)

(rule "100OHM_diff_outer" 
# calculated as 100Ohm @ 55 Ohm SE
	(constraint track_width (opt 0.16mm))
	(constraint diff_pair_gap (opt 0.15mm))
	(constraint clearance (opt 0.1mm))
	(condition "(A.NetClass == '100Ohm-diff') ")
	(layer outer)
)

(rule "90OHM_diff_outer" 
# calculated as 90Ohm @ 55 Ohm SE
	(constraint track_width (opt 0.2mm))
	(constraint diff_pair_gap (opt 0.13mm))
	(constraint clearance (opt 0.1mm))
	(condition "(A.NetClass == '90Ohm-diff') ")
	(layer outer)
)
